FILE_TYPE = MULTI_PHYS_TABLE;
PART 'AT24C64'
{========================================================================================}
:PACK_TYPE|MATERIAL|PART_NUMBER= EnvComp |PART_NUMBER|JEDEC_TYPE|CLASS|DESCRIPTION|COMPONENT_TYPE|HEIGHT|LEAD_LENGTH| LPID   | SPEED_URL | Status |RPL| AML | Bus_Unit | Days ;
{========================================================================================}
'SOICLF'      | 'IC'      | 'C47049-001'(!) = 'YES;YES;YES;UNK;ok;VLD' | 'C47049-001'   | 'SOI8_15_50IA'    | 'IC' | 'EEPROM'                | 'SOIC'         | '.069 IN' |      '' | '' | 'http://speed.intel.com:8081/speed/module/pdm/item/pdm_item_detail_direct.asp?item_cde=C47049-001&item_rev=01&url_param=unused' | 'Conditional' | 'YES' | '14' | 'SMO_IC' | '84' 
'SOIC'      | 'IC'      | 'C47049-001'(!) = 'YES;YES;YES;UNK;ok;VLD' | 'C47049-001'   | 'SOI8_15_50IA'    | 'IC' | 'EEPROM'                | 'SOIC'         | '.069 IN' |      '' | '' | 'http://speed.intel.com:8081/speed/module/pdm/item/pdm_item_detail_direct.asp?item_cde=C47049-001&item_rev=01&url_param=unused' | 'Conditional' | 'YES' | '14' | 'SMO_IC' | '84' 
'SOICLF'      | 'EMPTY'   | 'C47049-001'(!) = 'YES;YES;YES;UNK;ok;VLD' | 'C47049-001'   | 'SOI8_15_50IA'    | 'IO' | 'EEPROM'                | 'SOIC'         | '.069 IN' |      '' | '' | 'http://speed.intel.com:8081/speed/module/pdm/item/pdm_item_detail_direct.asp?item_cde=C47049-001&item_rev=01&url_param=unused' | 'Conditional' | 'YES' | '14' | 'SMO_IC' | '84' 
'SOIC'      | 'EMPTY'   | 'C47049-001'(!) = 'YES;YES;YES;UNK;ok;VLD' | 'C47049-001'   | 'SOI8_15_50IA'    | 'IO' | 'EEPROM'                | 'SOIC'         | '.069 IN' |      '' | '' | 'http://speed.intel.com:8081/speed/module/pdm/item/pdm_item_detail_direct.asp?item_cde=C47049-001&item_rev=01&url_param=unused' | 'Conditional' | 'YES' | '14' | 'SMO_IC' | '84' 
END_PART
END.
